# T6G (Grand Teton) — schematic netlist excerpt (pin names and nets, part order shuffled) for the footprints in the layout excerpt that follows; sources: Cadence DE-HDL packaged netlist, KiCad conversion of 04192023_DAF0TMB3IC0_F0TG_MB_C_brd_V02_OCP.brd

PC2147  Q_CAP  1UF 25V 10% X6S  pkg C0402  page 140 : A = GND ; B = P3V3_OCP_REG_2
PR3788  Q_RES  15K 1% CHIP  pkg 0402LF  page 134 : A = P12V_OCP_OV_1 ; B = GND

(kicad_pcb
	(version 20260206)
	(generator "pcbnew")
	(generator_version "10.0")
	(general
		(thickness 1.6)
		(legacy_teardrops no)
	)
	(paper "A4")
	(title_block
		(title "04192023_DAF0TMB3IC0_F0TG_MB_C_brd_V02_OCP.brd")
		(comment 1 "Grand Teton / footprints 3153-3154 of 8354")
	)
	(layers
		(0 "F.Cu" signal "TOP")
		(4 "In1.Cu" signal "GND")
		(6 "In2.Cu" signal "IN1")
		(8 "In3.Cu" signal "GND1")
		(10 "In4.Cu" signal "IN2")
		(12 "In5.Cu" signal "GND2")
		(14 "In6.Cu" signal "IN3")
		(16 "In7.Cu" signal "GND3")
		(18 "In8.Cu" signal "VCC")
		(20 "In9.Cu" signal "VCC1")
		(22 "In10.Cu" signal "GND4")
		(24 "In11.Cu" signal "IN4")
		(26 "In12.Cu" signal "GND5")
		(28 "In13.Cu" signal "IN5")
		(30 "In14.Cu" signal "GND6")
		(32 "In15.Cu" signal "IN6")
		(34 "In16.Cu" signal "GND7")
		(2 "B.Cu" signal "BOTTOM")
		(9 "F.Adhes" user "F.Adhesive")
		(11 "B.Adhes" user "B.Adhesive")
		(13 "F.Paste" user "Package Geometry/Pastemask Top")
		(15 "B.Paste" user "Package Geometry/Pastemask Bottom")
		(5 "F.SilkS" user "Ref Des/Silkscreen Top")
		(7 "B.SilkS" user "Ref Des/Silkscreen Bottom")
		(1 "F.Mask" user "Board Geometry/Soldermask Top")
		(3 "B.Mask" user "Board Geometry/Soldermask Bottom")
		(17 "Dwgs.User" user "User.Drawings")
		(19 "Cmts.User" user "User.Comments")
		(21 "Eco1.User" user "User.Eco1")
		(23 "Eco2.User" user "User.Eco2")
		(25 "Edge.Cuts" user "Board Geometry/Outline")
		(27 "Margin" user)
		(31 "F.CrtYd" user "Package Geometry/Place Bound Top")
		(29 "B.CrtYd" user "Package Geometry/Place Bound Bottom")
		(35 "F.Fab" user "Ref Des/Assembly Top")
		(33 "B.Fab" user "Ref Des/Assembly Bottom")
	)
	(footprint ""
		(layer "F.Cu")
		(at 95.38335 -59.80557 180)
		(property "Reference" "PC2147"
			(at 0 0 180)
			(layer "F.SilkS")
			(hide yes)
			(effects
				(font
					(size 1.27 1.27)
				)
			)
		)
		(property "Value" ""
			(at 0 0 180)
			(layer "F.Fab")
			(effects
				(font
					(size 1.27 1.27)
				)
			)
		)
		(duplicate_pad_numbers_are_jumpers no)
		(fp_line
			(start 0.7874 0.4064)
			(end -0.7874 0.4064)
			(stroke
				(width 0.1524)
				(type default)
			)
			(layer "F.SilkS")
		)
		(fp_line
			(start 0.7874 -0.4064)
			(end 0.7874 0.4064)
			(stroke
				(width 0.1524)
				(type default)
			)
			(layer "F.SilkS")
		)
		(fp_line
			(start -0.7874 0.4064)
			(end -0.7874 -0.4064)
			(stroke
				(width 0.1524)
				(type default)
			)
			(layer "F.SilkS")
		)
		(fp_line
			(start -0.7874 -0.4064)
			(end 0.7874 -0.4064)
			(stroke
				(width 0.1524)
				(type default)
			)
			(layer "F.SilkS")
		)
		(fp_line
			(start 0.67945 0.3048)
			(end 0.120396 0.3048)
			(stroke
				(width 0.1)
				(type default)
			)
			(layer "F.Fab")
		)
		(fp_line
			(start 0.67945 -0.3048)
			(end 0.67945 0.3048)
			(stroke
				(width 0.1)
				(type default)
			)
			(layer "F.Fab")
		)
		(fp_line
			(start 0.12065 -0.2794)
			(end 0.12065 -0.3048)
			(stroke
				(width 0.1)
				(type default)
			)
			(layer "F.Fab")
		)
		(fp_line
			(start 0.12065 -0.3048)
			(end 0.67945 -0.3048)
			(stroke
				(width 0.1)
				(type default)
			)
			(layer "F.Fab")
		)
		(fp_line
			(start 0.120396 0.3048)
			(end 0.120396 0.2794)
			(stroke
				(width 0.1)
				(type default)
			)
			(layer "F.Fab")
		)
		(fp_line
			(start 0.120396 0.2794)
			(end -0.12065 0.2794)
			(stroke
				(width 0.1)
				(type default)
			)
			(layer "F.Fab")
		)
		(fp_line
			(start -0.12065 0.3048)
			(end -0.67945 0.3048)
			(stroke
				(width 0.1)
				(type default)
			)
			(layer "F.Fab")
		)
		(fp_line
			(start -0.12065 0.2794)
			(end -0.12065 0.3048)
			(stroke
				(width 0.1)
				(type default)
			)
			(layer "F.Fab")
		)
		(fp_line
			(start -0.12065 -0.2794)
			(end 0.12065 -0.2794)
			(stroke
				(width 0.1)
				(type default)
			)
			(layer "F.Fab")
		)
		(fp_line
			(start -0.12065 -0.305054)
			(end -0.12065 -0.2794)
			(stroke
				(width 0.1)
				(type default)
			)
			(layer "F.Fab")
		)
		(fp_line
			(start -0.67945 0.3048)
			(end -0.67945 -0.305054)
			(stroke
				(width 0.1)
				(type default)
			)
			(layer "F.Fab")
		)
		(fp_line
			(start -0.67945 -0.305054)
			(end -0.12065 -0.305054)
			(stroke
				(width 0.1)
				(type default)
			)
			(layer "F.Fab")
		)
		(pad "1" smd circle
			(at -0.40005 0 180)
			(size 0 0)
			(layers "F.Cu" "F.Mask" "F.Paste")
			(net "GND")
		)
		(pad "2" smd circle
			(at 0.40005 0 180)
			(size 0 0)
			(layers "F.Cu" "F.Mask" "F.Paste")
			(net "P3V3_OCP_REG_2")
		)
	)
	(footprint ""
		(layer "F.Cu")
		(at 447.557652 -17.433798 180)
		(property "Reference" "PR3788"
			(at 0 0 180)
			(layer "F.SilkS")
			(hide yes)
			(effects
				(font
					(size 1.27 1.27)
				)
			)
		)
		(property "Value" ""
			(at 0 0 180)
			(layer "F.Fab")
			(effects
				(font
					(size 1.27 1.27)
				)
			)
		)
		(duplicate_pad_numbers_are_jumpers no)
		(fp_line
			(start 0.7874 0.4064)
			(end -0.7874 0.4064)
			(stroke
				(width 0.1524)
				(type default)
			)
			(layer "F.SilkS")
		)
		(fp_line
			(start 0.7874 -0.4064)
			(end 0.7874 0.4064)
			(stroke
				(width 0.1524)
				(type default)
			)
			(layer "F.SilkS")
		)
		(fp_line
			(start -0.7874 0.4064)
			(end -0.7874 -0.4064)
			(stroke
				(width 0.1524)
				(type default)
			)
			(layer "F.SilkS")
		)
		(fp_line
			(start -0.7874 -0.4064)
			(end 0.7874 -0.4064)
			(stroke
				(width 0.1524)
				(type default)
			)
			(layer "F.SilkS")
		)
		(fp_line
			(start 0.67945 0.3048)
			(end 0.120396 0.3048)
			(stroke
				(width 0.1)
				(type default)
			)
			(layer "F.Fab")
		)
		(fp_line
			(start 0.67945 -0.3048)
			(end 0.67945 0.3048)
			(stroke
				(width 0.1)
				(type default)
			)
			(layer "F.Fab")
		)
		(fp_line
			(start 0.12065 -0.2794)
			(end 0.12065 -0.3048)
			(stroke
				(width 0.1)
				(type default)
			)
			(layer "F.Fab")
		)
		(fp_line
			(start 0.12065 -0.3048)
			(end 0.67945 -0.3048)
			(stroke
				(width 0.1)
				(type default)
			)
			(layer "F.Fab")
		)
		(fp_line
			(start 0.120396 0.3048)
			(end 0.120396 0.2794)
			(stroke
				(width 0.1)
				(type default)
			)
			(layer "F.Fab")
		)
		(fp_line
			(start 0.120396 0.2794)
			(end -0.12065 0.2794)
			(stroke
				(width 0.1)
				(type default)
			)
			(layer "F.Fab")
		)
		(fp_line
			(start -0.12065 0.3048)
			(end -0.67945 0.3048)
			(stroke
				(width 0.1)
				(type default)
			)
			(layer "F.Fab")
		)
		(fp_line
			(start -0.12065 0.2794)
			(end -0.12065 0.3048)
			(stroke
				(width 0.1)
				(type default)
			)
			(layer "F.Fab")
		)
		(fp_line
			(start -0.12065 -0.2794)
			(end 0.12065 -0.2794)
			(stroke
				(width 0.1)
				(type default)
			)
			(layer "F.Fab")
		)
		(fp_line
			(start -0.12065 -0.305054)
			(end -0.12065 -0.2794)
			(stroke
				(width 0.1)
				(type default)
			)
			(layer "F.Fab")
		)
		(fp_line
			(start -0.67945 0.3048)
			(end -0.67945 -0.305054)
			(stroke
				(width 0.1)
				(type default)
			)
			(layer "F.Fab")
		)
		(fp_line
			(start -0.67945 -0.305054)
			(end -0.12065 -0.305054)
			(stroke
				(width 0.1)
				(type default)
			)
			(layer "F.Fab")
		)
		(pad "1" smd circle
			(at -0.40005 0 180)
			(size 0 0)
			(layers "F.Cu" "F.Mask" "F.Paste")
			(net "P12V_OCP_OV_1")
		)
		(pad "2" smd circle
			(at 0.40005 0 180)
			(size 0 0)
			(layers "F.Cu" "F.Mask" "F.Paste")
			(net "GND")
		)
	)
)
